(kicad_pcb
	(version 20260206)
	(generator "pcbnew")
	(generator_version "10.0")
	(general
		(thickness 1.6)
		(legacy_teardrops no)
	)
	(paper "A4")
	(title_block
		(title "03242023_DA0F0TMBIJ0_F0T_Motherboard_J_brd_V01_OCP.brd")
		(comment 1 "Grand Teton / footprints 5602-5607 of 6105")
	)
	(layers
		(0 "F.Cu" signal "TOP")
		(4 "In1.Cu" signal "GND")
		(6 "In2.Cu" signal "IN1")
		(8 "In3.Cu" signal "GND1")
		(10 "In4.Cu" signal "IN2")
		(12 "In5.Cu" signal "GND2")
		(14 "In6.Cu" signal "IN3")
		(16 "In7.Cu" signal "GND3")
		(18 "In8.Cu" signal "VCC")
		(20 "In9.Cu" signal "VCC1")
		(22 "In10.Cu" signal "GND4")
		(24 "In11.Cu" signal "IN4")
		(26 "In12.Cu" signal "GND5")
		(28 "In13.Cu" signal "IN5")
		(30 "In14.Cu" signal "GND6")
		(32 "In15.Cu" signal "IN6")
		(34 "In16.Cu" signal "GND7")
		(2 "B.Cu" signal "BOTTOM")
		(9 "F.Adhes" user "F.Adhesive")
		(11 "B.Adhes" user "B.Adhesive")
		(13 "F.Paste" user "Package Geometry/Pastemask Top")
		(15 "B.Paste" user "Package Geometry/Pastemask Bottom")
		(5 "F.SilkS" user "Ref Des/Silkscreen Top")
		(7 "B.SilkS" user "Ref Des/Silkscreen Bottom")
		(1 "F.Mask" user "Board Geometry/Soldermask Top")
		(3 "B.Mask" user "Board Geometry/Soldermask Bottom")
		(17 "Dwgs.User" user "User.Drawings")
		(19 "Cmts.User" user "User.Comments")
		(21 "Eco1.User" user "User.Eco1")
		(23 "Eco2.User" user "User.Eco2")
		(25 "Edge.Cuts" user "Board Geometry/Outline")
		(27 "Margin" user)
		(31 "F.CrtYd" user "Package Geometry/Place Bound Top")
		(29 "B.CrtYd" user "Package Geometry/Place Bound Bottom")
		(35 "F.Fab" user "Ref Des/Assembly Top")
		(33 "B.Fab" user "Ref Des/Assembly Bottom")
	)
	(footprint ""
		(layer "B.Cu")
		(at 109.944154 -411.438598 -90)
		(property "Reference" "C2336"
			(at 0 0 90)
			(layer "B.SilkS")
			(hide yes)
			(effects
				(font
					(size 1.27 1.27)
				)
				(justify mirror)
			)
		)
		(property "Value" ""
			(at 0 0 90)
			(layer "B.Fab")
			(effects
				(font
					(size 1.27 1.27)
				)
				(justify mirror)
			)
		)
		(duplicate_pad_numbers_are_jumpers no)
		(fp_line
			(start -0.7874 0.4064)
			(end 0.7874 0.4064)
			(stroke
				(width 0.1524)
				(type default)
			)
			(layer "B.SilkS")
		)
		(fp_line
			(start 0.7874 0.4064)
			(end 0.7874 -0.4064)
			(stroke
				(width 0.1524)
				(type default)
			)
			(layer "B.SilkS")
		)
		(fp_line
			(start -0.7874 -0.4064)
			(end -0.7874 0.4064)
			(stroke
				(width 0.1524)
				(type default)
			)
			(layer "B.SilkS")
		)
		(fp_line
			(start 0.7874 -0.4064)
			(end -0.7874 -0.4064)
			(stroke
				(width 0.1524)
				(type default)
			)
			(layer "B.SilkS")
		)
		(fp_line
			(start -0.67945 0.3048)
			(end -0.120396 0.3048)
			(stroke
				(width 0.1)
				(type default)
			)
			(layer "B.Fab")
		)
		(fp_line
			(start -0.120396 0.3048)
			(end -0.120396 0.2794)
			(stroke
				(width 0.1)
				(type default)
			)
			(layer "B.Fab")
		)
		(fp_line
			(start 0.12065 0.3048)
			(end 0.67945 0.3048)
			(stroke
				(width 0.1)
				(type default)
			)
			(layer "B.Fab")
		)
		(fp_line
			(start 0.67945 0.3048)
			(end 0.67945 -0.305054)
			(stroke
				(width 0.1)
				(type default)
			)
			(layer "B.Fab")
		)
		(fp_line
			(start -0.120396 0.2794)
			(end 0.12065 0.2794)
			(stroke
				(width 0.1)
				(type default)
			)
			(layer "B.Fab")
		)
		(fp_line
			(start 0.12065 0.2794)
			(end 0.12065 0.3048)
			(stroke
				(width 0.1)
				(type default)
			)
			(layer "B.Fab")
		)
		(fp_line
			(start -0.12065 -0.2794)
			(end -0.12065 -0.3048)
			(stroke
				(width 0.1)
				(type default)
			)
			(layer "B.Fab")
		)
		(fp_line
			(start 0.12065 -0.2794)
			(end -0.12065 -0.2794)
			(stroke
				(width 0.1)
				(type default)
			)
			(layer "B.Fab")
		)
		(fp_line
			(start -0.67945 -0.3048)
			(end -0.67945 0.3048)
			(stroke
				(width 0.1)
				(type default)
			)
			(layer "B.Fab")
		)
		(fp_line
			(start -0.12065 -0.3048)
			(end -0.67945 -0.3048)
			(stroke
				(width 0.1)
				(type default)
			)
			(layer "B.Fab")
		)
		(fp_line
			(start 0.12065 -0.305054)
			(end 0.12065 -0.2794)
			(stroke
				(width 0.1)
				(type default)
			)
			(layer "B.Fab")
		)
		(fp_line
			(start 0.67945 -0.305054)
			(end 0.12065 -0.305054)
			(stroke
				(width 0.1)
				(type default)
			)
			(layer "B.Fab")
		)
		(pad "1" smd circle
			(at 0.40005 0 90)
			(size 0 0)
			(layers "B.Cu" "B.Mask" "B.Paste")
			(net "P3V3_9ZXL045_VDD")
		)
		(pad "2" smd circle
			(at -0.40005 0 90)
			(size 0 0)
			(layers "B.Cu" "B.Mask" "B.Paste")
			(net "GND")
		)
	)
	(footprint ""
		(layer "B.Cu")
		(at 175.273208 -198.114158)
		(property "Reference" "R268"
			(at 0 0 0)
			(layer "B.SilkS")
			(hide yes)
			(effects
				(font
					(size 1.27 1.27)
				)
				(justify mirror)
			)
		)
		(property "Value" ""
			(at 0 0 0)
			(layer "B.Fab")
			(effects
				(font
					(size 1.27 1.27)
				)
				(justify mirror)
			)
		)
		(duplicate_pad_numbers_are_jumpers no)
		(fp_line
			(start -0.7874 -0.4064)
			(end -0.7874 0.4064)
			(stroke
				(width 0.1524)
				(type default)
			)
			(layer "B.SilkS")
		)
		(fp_line
			(start -0.7874 0.4064)
			(end 0.7874 0.4064)
			(stroke
				(width 0.1524)
				(type default)
			)
			(layer "B.SilkS")
		)
		(fp_line
			(start 0.7874 -0.4064)
			(end -0.7874 -0.4064)
			(stroke
				(width 0.1524)
				(type default)
			)
			(layer "B.SilkS")
		)
		(fp_line
			(start 0.7874 0.4064)
			(end 0.7874 -0.4064)
			(stroke
				(width 0.1524)
				(type default)
			)
			(layer "B.SilkS")
		)
		(fp_line
			(start -0.67945 -0.3048)
			(end -0.67945 0.3048)
			(stroke
				(width 0.1)
				(type default)
			)
			(layer "B.Fab")
		)
		(fp_line
			(start -0.67945 0.3048)
			(end -0.120396 0.3048)
			(stroke
				(width 0.1)
				(type default)
			)
			(layer "B.Fab")
		)
		(fp_line
			(start -0.12065 -0.3048)
			(end -0.67945 -0.3048)
			(stroke
				(width 0.1)
				(type default)
			)
			(layer "B.Fab")
		)
		(fp_line
			(start -0.12065 -0.2794)
			(end -0.12065 -0.3048)
			(stroke
				(width 0.1)
				(type default)
			)
			(layer "B.Fab")
		)
		(fp_line
			(start -0.120396 0.2794)
			(end 0.12065 0.2794)
			(stroke
				(width 0.1)
				(type default)
			)
			(layer "B.Fab")
		)
		(fp_line
			(start -0.120396 0.3048)
			(end -0.120396 0.2794)
			(stroke
				(width 0.1)
				(type default)
			)
			(layer "B.Fab")
		)
		(fp_line
			(start 0.12065 -0.305054)
			(end 0.12065 -0.2794)
			(stroke
				(width 0.1)
				(type default)
			)
			(layer "B.Fab")
		)
		(fp_line
			(start 0.12065 -0.2794)
			(end -0.12065 -0.2794)
			(stroke
				(width 0.1)
				(type default)
			)
			(layer "B.Fab")
		)
		(fp_line
			(start 0.12065 0.2794)
			(end 0.12065 0.3048)
			(stroke
				(width 0.1)
				(type default)
			)
			(layer "B.Fab")
		)
		(fp_line
			(start 0.12065 0.3048)
			(end 0.67945 0.3048)
			(stroke
				(width 0.1)
				(type default)
			)
			(layer "B.Fab")
		)
		(fp_line
			(start 0.67945 -0.305054)
			(end 0.12065 -0.305054)
			(stroke
				(width 0.1)
				(type default)
			)
			(layer "B.Fab")
		)
		(fp_line
			(start 0.67945 0.3048)
			(end 0.67945 -0.305054)
			(stroke
				(width 0.1)
				(type default)
			)
			(layer "B.Fab")
		)
		(pad "1" smd circle
			(at 0.40005 0 180)
			(size 0 0)
			(layers "B.Cu" "B.Mask" "B.Paste")
			(net "PVNN_TERM_CPU1")
		)
		(pad "2" smd circle
			(at -0.40005 0 180)
			(size 0 0)
			(layers "B.Cu" "B.Mask" "B.Paste")
			(net "PU_CPU1_LEGACY_SKT")
		)
	)
	(footprint ""
		(layer "B.Cu")
		(at 117.529102 -324.792086 -90)
		(property "Reference" "PC542_P1_3"
			(at 0 0 90)
			(layer "B.SilkS")
			(hide yes)
			(effects
				(font
					(size 1.27 1.27)
				)
				(justify mirror)
			)
		)
		(property "Value" ""
			(at 0 0 90)
			(layer "B.Fab")
			(effects
				(font
					(size 1.27 1.27)
				)
				(justify mirror)
			)
		)
		(duplicate_pad_numbers_are_jumpers no)
		(fp_line
			(start -1.524 0.762)
			(end 1.524 0.762)
			(stroke
				(width 0.1524)
				(type default)
			)
			(layer "B.SilkS")
		)
		(fp_line
			(start 1.524 0.762)
			(end 1.524 -0.762)
			(stroke
				(width 0.1524)
				(type default)
			)
			(layer "B.SilkS")
		)
		(fp_line
			(start -1.524 -0.762)
			(end -1.524 0.762)
			(stroke
				(width 0.1524)
				(type default)
			)
			(layer "B.SilkS")
		)
		(fp_line
			(start 1.524 -0.762)
			(end -1.524 -0.762)
			(stroke
				(width 0.1524)
				(type default)
			)
			(layer "B.SilkS")
		)
		(fp_line
			(start -1.1049 0.724916)
			(end -1.1049 -0.724916)
			(stroke
				(width 0.1)
				(type default)
			)
			(layer "B.Fab")
		)
		(fp_line
			(start 1.1049 0.724916)
			(end -1.1049 0.724916)
			(stroke
				(width 0.1)
				(type default)
			)
			(layer "B.Fab")
		)
		(fp_line
			(start -1.1049 -0.724916)
			(end 1.1049 -0.724916)
			(stroke
				(width 0.1)
				(type default)
			)
			(layer "B.Fab")
		)
		(fp_line
			(start 1.1049 -0.724916)
			(end 1.1049 0.724916)
			(stroke
				(width 0.1)
				(type default)
			)
			(layer "B.Fab")
		)
		(pad "1" smd rect
			(at 0.889 0 270)
			(size 1.016 1.27)
			(layers "B.Cu" "B.Mask" "B.Paste")
			(net "PVCCIN_CPU1")
		)
		(pad "2" smd rect
			(at -0.889 0 270)
			(size 1.016 1.27)
			(layers "B.Cu" "B.Mask" "B.Paste")
			(net "GND")
		)
	)
	(footprint ""
		(layer "B.Cu")
		(at 155.074112 -38.579552 180)
		(property "Reference" "C2320"
			(at 0 0 0)
			(layer "B.SilkS")
			(hide yes)
			(effects
				(font
					(size 1.27 1.27)
				)
				(justify mirror)
			)
		)
		(property "Value" ""
			(at 0 0 0)
			(layer "B.Fab")
			(effects
				(font
					(size 1.27 1.27)
				)
				(justify mirror)
			)
		)
		(duplicate_pad_numbers_are_jumpers no)
		(fp_line
			(start 0.7874 0.4064)
			(end 0.7874 -0.4064)
			(stroke
				(width 0.1524)
				(type default)
			)
			(layer "B.SilkS")
		)
		(fp_line
			(start 0.7874 -0.4064)
			(end -0.7874 -0.4064)
			(stroke
				(width 0.1524)
				(type default)
			)
			(layer "B.SilkS")
		)
		(fp_line
			(start -0.7874 0.4064)
			(end 0.7874 0.4064)
			(stroke
				(width 0.1524)
				(type default)
			)
			(layer "B.SilkS")
		)
		(fp_line
			(start -0.7874 -0.4064)
			(end -0.7874 0.4064)
			(stroke
				(width 0.1524)
				(type default)
			)
			(layer "B.SilkS")
		)
		(fp_line
			(start 0.67945 0.3048)
			(end 0.67945 -0.305054)
			(stroke
				(width 0.1)
				(type default)
			)
			(layer "B.Fab")
		)
		(fp_line
			(start 0.67945 -0.305054)
			(end 0.12065 -0.305054)
			(stroke
				(width 0.1)
				(type default)
			)
			(layer "B.Fab")
		)
		(fp_line
			(start 0.12065 0.3048)
			(end 0.67945 0.3048)
			(stroke
				(width 0.1)
				(type default)
			)
			(layer "B.Fab")
		)
		(fp_line
			(start 0.12065 0.2794)
			(end 0.12065 0.3048)
			(stroke
				(width 0.1)
				(type default)
			)
			(layer "B.Fab")
		)
		(fp_line
			(start 0.12065 -0.2794)
			(end -0.12065 -0.2794)
			(stroke
				(width 0.1)
				(type default)
			)
			(layer "B.Fab")
		)
		(fp_line
			(start 0.12065 -0.305054)
			(end 0.12065 -0.2794)
			(stroke
				(width 0.1)
				(type default)
			)
			(layer "B.Fab")
		)
		(fp_line
			(start -0.120396 0.3048)
			(end -0.120396 0.2794)
			(stroke
				(width 0.1)
				(type default)
			)
			(layer "B.Fab")
		)
		(fp_line
			(start -0.120396 0.2794)
			(end 0.12065 0.2794)
			(stroke
				(width 0.1)
				(type default)
			)
			(layer "B.Fab")
		)
		(fp_line
			(start -0.12065 -0.2794)
			(end -0.12065 -0.3048)
			(stroke
				(width 0.1)
				(type default)
			)
			(layer "B.Fab")
		)
		(fp_line
			(start -0.12065 -0.3048)
			(end -0.67945 -0.3048)
			(stroke
				(width 0.1)
				(type default)
			)
			(layer "B.Fab")
		)
		(fp_line
			(start -0.67945 0.3048)
			(end -0.120396 0.3048)
			(stroke
				(width 0.1)
				(type default)
			)
			(layer "B.Fab")
		)
		(fp_line
			(start -0.67945 -0.3048)
			(end -0.67945 0.3048)
			(stroke
				(width 0.1)
				(type default)
			)
			(layer "B.Fab")
		)
		(pad "1" smd circle
			(at 0.40005 0)
			(size 0 0)
			(layers "B.Cu" "B.Mask" "B.Paste")
			(net "P3V3_AUX_USB_HUB_2")
		)
		(pad "2" smd circle
			(at -0.40005 0)
			(size 0 0)
			(layers "B.Cu" "B.Mask" "B.Paste")
			(net "GND")
		)
	)
	(footprint ""
		(layer "B.Cu")
		(at 154.21102 -227.427536 180)
		(property "Reference" "R962"
			(at 0 0 0)
			(layer "B.SilkS")
			(hide yes)
			(effects
				(font
					(size 1.27 1.27)
				)
				(justify mirror)
			)
		)
		(property "Value" ""
			(at 0 0 0)
			(layer "B.Fab")
			(effects
				(font
					(size 1.27 1.27)
				)
				(justify mirror)
			)
		)
		(duplicate_pad_numbers_are_jumpers no)
		(fp_line
			(start 0.7874 0.4064)
			(end 0.7874 -0.4064)
			(stroke
				(width 0.1524)
				(type default)
			)
			(layer "B.SilkS")
		)
		(fp_line
			(start 0.7874 -0.4064)
			(end -0.7874 -0.4064)
			(stroke
				(width 0.1524)
				(type default)
			)
			(layer "B.SilkS")
		)
		(fp_line
			(start -0.7874 0.4064)
			(end 0.7874 0.4064)
			(stroke
				(width 0.1524)
				(type default)
			)
			(layer "B.SilkS")
		)
		(fp_line
			(start -0.7874 -0.4064)
			(end -0.7874 0.4064)
			(stroke
				(width 0.1524)
				(type default)
			)
			(layer "B.SilkS")
		)
		(fp_line
			(start 0.67945 0.3048)
			(end 0.67945 -0.305054)
			(stroke
				(width 0.1)
				(type default)
			)
			(layer "B.Fab")
		)
		(fp_line
			(start 0.67945 -0.305054)
			(end 0.12065 -0.305054)
			(stroke
				(width 0.1)
				(type default)
			)
			(layer "B.Fab")
		)
		(fp_line
			(start 0.12065 0.3048)
			(end 0.67945 0.3048)
			(stroke
				(width 0.1)
				(type default)
			)
			(layer "B.Fab")
		)
		(fp_line
			(start 0.12065 0.2794)
			(end 0.12065 0.3048)
			(stroke
				(width 0.1)
				(type default)
			)
			(layer "B.Fab")
		)
		(fp_line
			(start 0.12065 -0.2794)
			(end -0.12065 -0.2794)
			(stroke
				(width 0.1)
				(type default)
			)
			(layer "B.Fab")
		)
		(fp_line
			(start 0.12065 -0.305054)
			(end 0.12065 -0.2794)
			(stroke
				(width 0.1)
				(type default)
			)
			(layer "B.Fab")
		)
		(fp_line
			(start -0.120396 0.3048)
			(end -0.120396 0.2794)
			(stroke
				(width 0.1)
				(type default)
			)
			(layer "B.Fab")
		)
		(fp_line
			(start -0.120396 0.2794)
			(end 0.12065 0.2794)
			(stroke
				(width 0.1)
				(type default)
			)
			(layer "B.Fab")
		)
		(fp_line
			(start -0.12065 -0.2794)
			(end -0.12065 -0.3048)
			(stroke
				(width 0.1)
				(type default)
			)
			(layer "B.Fab")
		)
		(fp_line
			(start -0.12065 -0.3048)
			(end -0.67945 -0.3048)
			(stroke
				(width 0.1)
				(type default)
			)
			(layer "B.Fab")
		)
		(fp_line
			(start -0.67945 0.3048)
			(end -0.120396 0.3048)
			(stroke
				(width 0.1)
				(type default)
			)
			(layer "B.Fab")
		)
		(fp_line
			(start -0.67945 -0.3048)
			(end -0.67945 0.3048)
			(stroke
				(width 0.1)
				(type default)
			)
			(layer "B.Fab")
		)
		(pad "1" smd circle
			(at 0.40005 0)
			(size 0 0)
			(layers "B.Cu" "B.Mask" "B.Paste")
			(net "SMB_PEHPCPU1_GTL_SDA")
		)
		(pad "2" smd circle
			(at -0.40005 0)
			(size 0 0)
			(layers "B.Cu" "B.Mask" "B.Paste")
			(net "SMB_PEHPCPU1_GTL_R_SDA")
		)
	)
	(footprint ""
		(layer "B.Cu")
		(at 304.138584 -153.501344 -90)
		(property "Reference" "R684"
			(at 0 0 90)
			(layer "B.SilkS")
			(hide yes)
			(effects
				(font
					(size 1.27 1.27)
				)
				(justify mirror)
			)
		)
		(property "Value" ""
			(at 0 0 90)
			(layer "B.Fab")
			(effects
				(font
					(size 1.27 1.27)
				)
				(justify mirror)
			)
		)
		(duplicate_pad_numbers_are_jumpers no)
		(fp_line
			(start -0.7874 0.4064)
			(end 0.7874 0.4064)
			(stroke
				(width 0.1524)
				(type default)
			)
			(layer "B.SilkS")
		)
		(fp_line
			(start 0.7874 0.4064)
			(end 0.7874 -0.4064)
			(stroke
				(width 0.1524)
				(type default)
			)
			(layer "B.SilkS")
		)
		(fp_line
			(start -0.7874 -0.4064)
			(end -0.7874 0.4064)
			(stroke
				(width 0.1524)
				(type default)
			)
			(layer "B.SilkS")
		)
		(fp_line
			(start 0.7874 -0.4064)
			(end -0.7874 -0.4064)
			(stroke
				(width 0.1524)
				(type default)
			)
			(layer "B.SilkS")
		)
		(fp_line
			(start -0.67945 0.3048)
			(end -0.120396 0.3048)
			(stroke
				(width 0.1)
				(type default)
			)
			(layer "B.Fab")
		)
		(fp_line
			(start -0.120396 0.3048)
			(end -0.120396 0.2794)
			(stroke
				(width 0.1)
				(type default)
			)
			(layer "B.Fab")
		)
		(fp_line
			(start 0.12065 0.3048)
			(end 0.67945 0.3048)
			(stroke
				(width 0.1)
				(type default)
			)
			(layer "B.Fab")
		)
		(fp_line
			(start 0.67945 0.3048)
			(end 0.67945 -0.305054)
			(stroke
				(width 0.1)
				(type default)
			)
			(layer "B.Fab")
		)
		(fp_line
			(start -0.120396 0.2794)
			(end 0.12065 0.2794)
			(stroke
				(width 0.1)
				(type default)
			)
			(layer "B.Fab")
		)
		(fp_line
			(start 0.12065 0.2794)
			(end 0.12065 0.3048)
			(stroke
				(width 0.1)
				(type default)
			)
			(layer "B.Fab")
		)
		(fp_line
			(start -0.12065 -0.2794)
			(end -0.12065 -0.3048)
			(stroke
				(width 0.1)
				(type default)
			)
			(layer "B.Fab")
		)
		(fp_line
			(start 0.12065 -0.2794)
			(end -0.12065 -0.2794)
			(stroke
				(width 0.1)
				(type default)
			)
			(layer "B.Fab")
		)
		(fp_line
			(start -0.67945 -0.3048)
			(end -0.67945 0.3048)
			(stroke
				(width 0.1)
				(type default)
			)
			(layer "B.Fab")
		)
		(fp_line
			(start -0.12065 -0.3048)
			(end -0.67945 -0.3048)
			(stroke
				(width 0.1)
				(type default)
			)
			(layer "B.Fab")
		)
		(fp_line
			(start 0.12065 -0.305054)
			(end 0.12065 -0.2794)
			(stroke
				(width 0.1)
				(type default)
			)
			(layer "B.Fab")
		)
		(fp_line
			(start 0.67945 -0.305054)
			(end 0.12065 -0.305054)
			(stroke
				(width 0.1)
				(type default)
			)
			(layer "B.Fab")
		)
		(pad "1" smd circle
			(at 0.40005 0 90)
			(size 0 0)
			(layers "B.Cu" "B.Mask" "B.Paste")
			(net "I3C_SPD_DDREFGH_CPU0_R_SCL")
		)
		(pad "2" smd circle
			(at -0.40005 0 90)
			(size 0 0)
			(layers "B.Cu" "B.Mask" "B.Paste")
			(net "I3C_SPD_DDREFGH_CPU0_LVC1_R_SCL")
		)
	)
)
